(kicad_pcb
	(version 20241229)
	(generator "pcbnew")
	(generator_version "9.0")
	(general
		(thickness 1.62)
		(legacy_teardrops no)
	)
	(paper "A3")
	(title_block
		(title "COM Express 7 Baseboard")
		(date "2025-02-04")
		(rev "1.1.2")
		(company "Antmicro Ltd")
		(comment 1 "www.antmicro.com")
		(comment 9 "footprint 489 of 802 (J12), pads 407-447 of 450")
	)
	(layers
		(0 "F.Cu" signal)
		(4 "In1.Cu" signal)
		(6 "In2.Cu" signal)
		(8 "In3.Cu" signal)
		(10 "In4.Cu" signal)
		(12 "In5.Cu" signal)
		(14 "In6.Cu" signal)
		(2 "B.Cu" signal)
		(9 "F.Adhes" user "F.Adhesive")
		(11 "B.Adhes" user "B.Adhesive")
		(13 "F.Paste" user)
		(15 "B.Paste" user)
		(5 "F.SilkS" user "F.Silkscreen")
		(7 "B.SilkS" user "B.Silkscreen")
		(1 "F.Mask" user)
		(3 "B.Mask" user)
		(17 "Dwgs.User" user "User.Drawings")
		(19 "Cmts.User" user "User.Comments")
		(21 "Eco1.User" user "User.Eco1")
		(23 "Eco2.User" user "User.Eco2")
		(25 "Edge.Cuts" user)
		(27 "Margin" user)
		(31 "F.CrtYd" user "F.Courtyard")
		(29 "B.CrtYd" user "B.Courtyard")
		(35 "F.Fab" user)
		(33 "B.Fab" user)
	)
	(footprint "antmicro-footprints:EPT_401-51501-51"
		(layer "F.Cu")
		(at 203.275 159.81)
		(property "Reference" "J12"
			(at 30.975 -10.45 0)
			(layer "F.SilkS")
			(effects
				(font
					(size 0.7 0.7)
					(thickness 0.15)
				)
				(justify right top)
			)
		)
		(property "Value" "Plug_Bus_CE7_EPT_401-51501-51"
			(at -3.225 52.665 0)
			(layer "F.Fab")
			(hide yes)
			(effects
				(font
					(size 0.7 0.7)
					(thickness 0.15)
				)
				(justify left top)
			)
		)
		(property "Datasheet" "https://www.farnell.com/datasheets/1905093.pdf"
			(at 0 0 0)
			(layer "F.Fab")
			(hide yes)
			(effects
				(font
					(size 1.27 1.27)
					(thickness 0.15)
				)
			)
		)
		(property "Author" "Antmicro"
			(at 406.55 319.62 0)
			(layer "F.Fab")
			(hide yes)
			(effects
				(font
					(size 1 1)
					(thickness 0.15)
				)
			)
		)
		(property "License" "Apache-2.0"
			(at 406.55 319.62 0)
			(layer "F.Fab")
			(hide yes)
			(effects
				(font
					(size 1 1)
					(thickness 0.15)
				)
			)
		)
		(property "MPN" "401-51501-51"
			(at 406.55 319.62 0)
			(layer "F.Fab")
			(hide yes)
			(effects
				(font
					(size 1 1)
					(thickness 0.15)
				)
			)
		)
		(property "Manufacturer" "ept"
			(at 406.55 319.62 0)
			(layer "F.Fab")
			(hide yes)
			(effects
				(font
					(size 1 1)
					(thickness 0.15)
				)
			)
		)
		(sheetname "Com Express 7 Interfaces")
		(sheetfile "com_express_7_interfaces.kicad_sch")
		(attr smd)
		(pad "D72" smd rect
			(at 8.25 -8.675)
			(size 0.3 1.75)
			(layers "F.Cu" "F.Mask" "F.Paste")
			(net 501 "unconnected-(J12N-PCIE_TX22--PadD72)")
			(pinfunction "PCIE_TX22-")
			(pintype "output+no_connect")
			(teardrops
				(best_length_ratio 0.2)
				(max_length 1)
				(best_width_ratio 0.9)
				(max_width 2)
				(curved_edges yes)
				(filter_ratio 0.9)
				(enabled yes)
				(allow_two_segments yes)
				(prefer_zone_connections yes)
			)
		)
		(pad "D73" smd rect
			(at 8.75 -8.675)
			(size 0.3 1.75)
			(layers "F.Cu" "F.Mask" "F.Paste")
			(net 1 "GND")
			(pinfunction "GND")
			(pintype "passive")
			(teardrops
				(best_length_ratio 0.2)
				(max_length 1)
				(best_width_ratio 0.9)
				(max_width 2)
				(curved_edges yes)
				(filter_ratio 0.9)
				(enabled yes)
				(allow_two_segments yes)
				(prefer_zone_connections yes)
			)
		)
		(pad "D74" smd rect
			(at 9.25 -8.675)
			(size 0.3 1.75)
			(layers "F.Cu" "F.Mask" "F.Paste")
			(net 502 "unconnected-(J12N-PCIE_TX23+-PadD74)")
			(pinfunction "PCIE_TX23+")
			(pintype "output+no_connect")
			(teardrops
				(best_length_ratio 0.2)
				(max_length 1)
				(best_width_ratio 0.9)
				(max_width 2)
				(curved_edges yes)
				(filter_ratio 0.9)
				(enabled yes)
				(allow_two_segments yes)
				(prefer_zone_connections yes)
			)
		)
		(pad "D75" smd rect
			(at 9.75 -8.675)
			(size 0.3 1.75)
			(layers "F.Cu" "F.Mask" "F.Paste")
			(net 503 "unconnected-(J12N-PCIE_TX23--PadD75)")
			(pinfunction "PCIE_TX23-")
			(pintype "output+no_connect")
			(teardrops
				(best_length_ratio 0.2)
				(max_length 1)
				(best_width_ratio 0.9)
				(max_width 2)
				(curved_edges yes)
				(filter_ratio 0.9)
				(enabled yes)
				(allow_two_segments yes)
				(prefer_zone_connections yes)
			)
		)
		(pad "D76" smd rect
			(at 10.25 -8.675)
			(size 0.3 1.75)
			(layers "F.Cu" "F.Mask" "F.Paste")
			(net 1 "GND")
			(pinfunction "GND")
			(pintype "passive")
			(teardrops
				(best_length_ratio 0.2)
				(max_length 1)
				(best_width_ratio 0.9)
				(max_width 2)
				(curved_edges yes)
				(filter_ratio 0.9)
				(enabled yes)
				(allow_two_segments yes)
				(prefer_zone_connections yes)
			)
		)
		(pad "D77" smd rect
			(at 10.75 -8.675)
			(size 0.3 1.75)
			(layers "F.Cu" "F.Mask" "F.Paste")
			(net 504 "unconnected-(J12M-RSVD-PadD77)")
			(pinfunction "RSVD")
			(pintype "no_connect")
			(teardrops
				(best_length_ratio 0.2)
				(max_length 1)
				(best_width_ratio 0.9)
				(max_width 2)
				(curved_edges yes)
				(filter_ratio 0.9)
				(enabled yes)
				(allow_two_segments yes)
				(prefer_zone_connections yes)
			)
		)
		(pad "D78" smd rect
			(at 11.25 -8.675)
			(size 0.3 1.75)
			(layers "F.Cu" "F.Mask" "F.Paste")
			(net 505 "unconnected-(J12N-PCIE_TX24+-PadD78)")
			(pinfunction "PCIE_TX24+")
			(pintype "output+no_connect")
			(teardrops
				(best_length_ratio 0.2)
				(max_length 1)
				(best_width_ratio 0.9)
				(max_width 2)
				(curved_edges yes)
				(filter_ratio 0.9)
				(enabled yes)
				(allow_two_segments yes)
				(prefer_zone_connections yes)
			)
		)
		(pad "D79" smd rect
			(at 11.75 -8.675)
			(size 0.3 1.75)
			(layers "F.Cu" "F.Mask" "F.Paste")
			(net 506 "unconnected-(J12N-PCIE_TX24--PadD79)")
			(pinfunction "PCIE_TX24-")
			(pintype "output+no_connect")
			(teardrops
				(best_length_ratio 0.2)
				(max_length 1)
				(best_width_ratio 0.9)
				(max_width 2)
				(curved_edges yes)
				(filter_ratio 0.9)
				(enabled yes)
				(allow_two_segments yes)
				(prefer_zone_connections yes)
			)
		)
		(pad "D80" smd rect
			(at 12.25 -8.675)
			(size 0.3 1.75)
			(layers "F.Cu" "F.Mask" "F.Paste")
			(net 1 "GND")
			(pinfunction "GND(FIXED)")
			(pintype "passive")
			(teardrops
				(best_length_ratio 0.2)
				(max_length 1)
				(best_width_ratio 0.9)
				(max_width 2)
				(curved_edges yes)
				(filter_ratio 0.9)
				(enabled yes)
				(allow_two_segments yes)
				(prefer_zone_connections yes)
			)
		)
		(pad "D81" smd rect
			(at 12.75 -8.675)
			(size 0.3 1.75)
			(layers "F.Cu" "F.Mask" "F.Paste")
			(net 507 "unconnected-(J12N-PCIE_TX25+-PadD81)")
			(pinfunction "PCIE_TX25+")
			(pintype "output+no_connect")
			(teardrops
				(best_length_ratio 0.2)
				(max_length 1)
				(best_width_ratio 0.9)
				(max_width 2)
				(curved_edges yes)
				(filter_ratio 0.9)
				(enabled yes)
				(allow_two_segments yes)
				(prefer_zone_connections yes)
			)
		)
		(pad "D82" smd rect
			(at 13.25 -8.675)
			(size 0.3 1.75)
			(layers "F.Cu" "F.Mask" "F.Paste")
			(net 508 "unconnected-(J12N-PCIE_TX25--PadD82)")
			(pinfunction "PCIE_TX25-")
			(pintype "output+no_connect")
			(teardrops
				(best_length_ratio 0.2)
				(max_length 1)
				(best_width_ratio 0.9)
				(max_width 2)
				(curved_edges yes)
				(filter_ratio 0.9)
				(enabled yes)
				(allow_two_segments yes)
				(prefer_zone_connections yes)
			)
		)
		(pad "D83" smd rect
			(at 13.75 -8.675)
			(size 0.3 1.75)
			(layers "F.Cu" "F.Mask" "F.Paste")
			(net 509 "unconnected-(J12M-RSVD-PadD83)")
			(pinfunction "RSVD")
			(pintype "no_connect")
			(teardrops
				(best_length_ratio 0.2)
				(max_length 1)
				(best_width_ratio 0.9)
				(max_width 2)
				(curved_edges yes)
				(filter_ratio 0.9)
				(enabled yes)
				(allow_two_segments yes)
				(prefer_zone_connections yes)
			)
		)
		(pad "D84" smd rect
			(at 14.25 -8.675)
			(size 0.3 1.75)
			(layers "F.Cu" "F.Mask" "F.Paste")
			(net 1 "GND")
			(pinfunction "GND")
			(pintype "passive")
			(teardrops
				(best_length_ratio 0.2)
				(max_length 1)
				(best_width_ratio 0.9)
				(max_width 2)
				(curved_edges yes)
				(filter_ratio 0.9)
				(enabled yes)
				(allow_two_segments yes)
				(prefer_zone_connections yes)
			)
		)
		(pad "D85" smd rect
			(at 14.75 -8.675)
			(size 0.3 1.75)
			(layers "F.Cu" "F.Mask" "F.Paste")
			(net 510 "unconnected-(J12N-PCIE_TX26+-PadD85)")
			(pinfunction "PCIE_TX26+")
			(pintype "output+no_connect")
			(teardrops
				(best_length_ratio 0.2)
				(max_length 1)
				(best_width_ratio 0.9)
				(max_width 2)
				(curved_edges yes)
				(filter_ratio 0.9)
				(enabled yes)
				(allow_two_segments yes)
				(prefer_zone_connections yes)
			)
		)
		(pad "D86" smd rect
			(at 15.25 -8.675)
			(size 0.3 1.75)
			(layers "F.Cu" "F.Mask" "F.Paste")
			(net 511 "unconnected-(J12N-PCIE_TX26--PadD86)")
			(pinfunction "PCIE_TX26-")
			(pintype "output+no_connect")
			(teardrops
				(best_length_ratio 0.2)
				(max_length 1)
				(best_width_ratio 0.9)
				(max_width 2)
				(curved_edges yes)
				(filter_ratio 0.9)
				(enabled yes)
				(allow_two_segments yes)
				(prefer_zone_connections yes)
			)
		)
		(pad "D87" smd rect
			(at 15.75 -8.675)
			(size 0.3 1.75)
			(layers "F.Cu" "F.Mask" "F.Paste")
			(net 1 "GND")
			(pinfunction "GND")
			(pintype "passive")
			(teardrops
				(best_length_ratio 0.2)
				(max_length 1)
				(best_width_ratio 0.9)
				(max_width 2)
				(curved_edges yes)
				(filter_ratio 0.9)
				(enabled yes)
				(allow_two_segments yes)
				(prefer_zone_connections yes)
			)
		)
		(pad "D88" smd rect
			(at 16.25 -8.675)
			(size 0.3 1.75)
			(layers "F.Cu" "F.Mask" "F.Paste")
			(net 512 "unconnected-(J12N-PCIE_TX27+-PadD88)")
			(pinfunction "PCIE_TX27+")
			(pintype "output+no_connect")
			(teardrops
				(best_length_ratio 0.2)
				(max_length 1)
				(best_width_ratio 0.9)
				(max_width 2)
				(curved_edges yes)
				(filter_ratio 0.9)
				(enabled yes)
				(allow_two_segments yes)
				(prefer_zone_connections yes)
			)
		)
		(pad "D89" smd rect
			(at 16.75 -8.675)
			(size 0.3 1.75)
			(layers "F.Cu" "F.Mask" "F.Paste")
			(net 513 "unconnected-(J12N-PCIE_TX27--PadD89)")
			(pinfunction "PCIE_TX27-")
			(pintype "output+no_connect")
			(teardrops
				(best_length_ratio 0.2)
				(max_length 1)
				(best_width_ratio 0.9)
				(max_width 2)
				(curved_edges yes)
				(filter_ratio 0.9)
				(enabled yes)
				(allow_two_segments yes)
				(prefer_zone_connections yes)
			)
		)
		(pad "D90" smd rect
			(at 17.25 -8.675)
			(size 0.3 1.75)
			(layers "F.Cu" "F.Mask" "F.Paste")
			(net 1 "GND")
			(pinfunction "GND(FIXED)")
			(pintype "passive")
			(teardrops
				(best_length_ratio 0.2)
				(max_length 1)
				(best_width_ratio 0.9)
				(max_width 2)
				(curved_edges yes)
				(filter_ratio 0.9)
				(enabled yes)
				(allow_two_segments yes)
				(prefer_zone_connections yes)
			)
		)
		(pad "D91" smd rect
			(at 17.75 -8.675)
			(size 0.3 1.75)
			(layers "F.Cu" "F.Mask" "F.Paste")
			(net 514 "unconnected-(J12N-PCIE_TX28+-PadD91)")
			(pinfunction "PCIE_TX28+")
			(pintype "output+no_connect")
			(teardrops
				(best_length_ratio 0.2)
				(max_length 1)
				(best_width_ratio 0.9)
				(max_width 2)
				(curved_edges yes)
				(filter_ratio 0.9)
				(enabled yes)
				(allow_two_segments yes)
				(prefer_zone_connections yes)
			)
		)
		(pad "D92" smd rect
			(at 18.25 -8.675)
			(size 0.3 1.75)
			(layers "F.Cu" "F.Mask" "F.Paste")
			(net 515 "unconnected-(J12N-PCIE_TX28--PadD92)")
			(pinfunction "PCIE_TX28-")
			(pintype "output+no_connect")
			(teardrops
				(best_length_ratio 0.2)
				(max_length 1)
				(best_width_ratio 0.9)
				(max_width 2)
				(curved_edges yes)
				(filter_ratio 0.9)
				(enabled yes)
				(allow_two_segments yes)
				(prefer_zone_connections yes)
			)
		)
		(pad "D93" smd rect
			(at 18.75 -8.675)
			(size 0.3 1.75)
			(layers "F.Cu" "F.Mask" "F.Paste")
			(net 1 "GND")
			(pinfunction "GND")
			(pintype "passive")
			(teardrops
				(best_length_ratio 0.2)
				(max_length 1)
				(best_width_ratio 0.9)
				(max_width 2)
				(curved_edges yes)
				(filter_ratio 0.9)
				(enabled yes)
				(allow_two_segments yes)
				(prefer_zone_connections yes)
			)
		)
		(pad "D94" smd rect
			(at 19.25 -8.675)
			(size 0.3 1.75)
			(layers "F.Cu" "F.Mask" "F.Paste")
			(net 516 "unconnected-(J12N-PCIE_TX29+-PadD94)")
			(pinfunction "PCIE_TX29+")
			(pintype "output+no_connect")
			(teardrops
				(best_length_ratio 0.2)
				(max_length 1)
				(best_width_ratio 0.9)
				(max_width 2)
				(curved_edges yes)
				(filter_ratio 0.9)
				(enabled yes)
				(allow_two_segments yes)
				(prefer_zone_connections yes)
			)
		)
		(pad "D95" smd rect
			(at 19.75 -8.675)
			(size 0.3 1.75)
			(layers "F.Cu" "F.Mask" "F.Paste")
			(net 517 "unconnected-(J12N-PCIE_TX29--PadD95)")
			(pinfunction "PCIE_TX29-")
			(pintype "output+no_connect")
			(teardrops
				(best_length_ratio 0.2)
				(max_length 1)
				(best_width_ratio 0.9)
				(max_width 2)
				(curved_edges yes)
				(filter_ratio 0.9)
				(enabled yes)
				(allow_two_segments yes)
				(prefer_zone_connections yes)
			)
		)
		(pad "D96" smd rect
			(at 20.25 -8.675)
			(size 0.3 1.75)
			(layers "F.Cu" "F.Mask" "F.Paste")
			(net 1 "GND")
			(pinfunction "GND")
			(pintype "passive")
			(teardrops
				(best_length_ratio 0.2)
				(max_length 1)
				(best_width_ratio 0.9)
				(max_width 2)
				(curved_edges yes)
				(filter_ratio 0.9)
				(enabled yes)
				(allow_two_segments yes)
				(prefer_zone_connections yes)
			)
		)
		(pad "D97" smd rect
			(at 20.75 -8.675)
			(size 0.3 1.75)
			(layers "F.Cu" "F.Mask" "F.Paste")
			(net 518 "unconnected-(J12M-RSVD-PadD97)")
			(pinfunction "RSVD")
			(pintype "no_connect")
			(teardrops
				(best_length_ratio 0.2)
				(max_length 1)
				(best_width_ratio 0.9)
				(max_width 2)
				(curved_edges yes)
				(filter_ratio 0.9)
				(enabled yes)
				(allow_two_segments yes)
				(prefer_zone_connections yes)
			)
		)
		(pad "D98" smd rect
			(at 21.25 -8.675)
			(size 0.3 1.75)
			(layers "F.Cu" "F.Mask" "F.Paste")
			(net 519 "unconnected-(J12N-PCIE_TX30+-PadD98)")
			(pinfunction "PCIE_TX30+")
			(pintype "output+no_connect")
			(teardrops
				(best_length_ratio 0.2)
				(max_length 1)
				(best_width_ratio 0.9)
				(max_width 2)
				(curved_edges yes)
				(filter_ratio 0.9)
				(enabled yes)
				(allow_two_segments yes)
				(prefer_zone_connections yes)
			)
		)
		(pad "D99" smd rect
			(at 21.75 -8.675)
			(size 0.3 1.75)
			(layers "F.Cu" "F.Mask" "F.Paste")
			(net 520 "unconnected-(J12N-PCIE_TX30--PadD99)")
			(pinfunction "PCIE_TX30-")
			(pintype "output+no_connect")
			(teardrops
				(best_length_ratio 0.2)
				(max_length 1)
				(best_width_ratio 0.9)
				(max_width 2)
				(curved_edges yes)
				(filter_ratio 0.9)
				(enabled yes)
				(allow_two_segments yes)
				(prefer_zone_connections yes)
			)
		)
		(pad "D100" smd rect
			(at 22.25 -8.675)
			(size 0.3 1.75)
			(layers "F.Cu" "F.Mask" "F.Paste")
			(net 1 "GND")
			(pinfunction "GND(FIXED)")
			(pintype "passive")
			(teardrops
				(best_length_ratio 0.2)
				(max_length 1)
				(best_width_ratio 0.9)
				(max_width 2)
				(curved_edges yes)
				(filter_ratio 0.9)
				(enabled yes)
				(allow_two_segments yes)
				(prefer_zone_connections yes)
			)
		)
		(pad "D101" smd rect
			(at 22.75 -8.675)
			(size 0.3 1.75)
			(layers "F.Cu" "F.Mask" "F.Paste")
			(net 521 "unconnected-(J12N-PCIE_TX31+-PadD101)")
			(pinfunction "PCIE_TX31+")
			(pintype "output+no_connect")
			(teardrops
				(best_length_ratio 0.2)
				(max_length 1)
				(best_width_ratio 0.9)
				(max_width 2)
				(curved_edges yes)
				(filter_ratio 0.9)
				(enabled yes)
				(allow_two_segments yes)
				(prefer_zone_connections yes)
			)
		)
		(pad "D102" smd rect
			(at 23.25 -8.675)
			(size 0.3 1.75)
			(layers "F.Cu" "F.Mask" "F.Paste")
			(net 522 "unconnected-(J12N-PCIE_TX31--PadD102)")
			(pinfunction "PCIE_TX31-")
			(pintype "output+no_connect")
			(teardrops
				(best_length_ratio 0.2)
				(max_length 1)
				(best_width_ratio 0.9)
				(max_width 2)
				(curved_edges yes)
				(filter_ratio 0.9)
				(enabled yes)
				(allow_two_segments yes)
				(prefer_zone_connections yes)
			)
		)
		(pad "D103" smd rect
			(at 23.75 -8.675)
			(size 0.3 1.75)
			(layers "F.Cu" "F.Mask" "F.Paste")
			(net 1 "GND")
			(pinfunction "GND")
			(pintype "passive")
			(teardrops
				(best_length_ratio 0.2)
				(max_length 1)
				(best_width_ratio 0.9)
				(max_width 2)
				(curved_edges yes)
				(filter_ratio 0.9)
				(enabled yes)
				(allow_two_segments yes)
				(prefer_zone_connections yes)
			)
		)
		(pad "D104" smd rect
			(at 24.25 -8.675)
			(size 0.3 1.75)
			(layers "F.Cu" "F.Mask" "F.Paste")
			(net 65 "+12V")
			(pinfunction "VCC_12V")
			(pintype "passive")
			(teardrops
				(best_length_ratio 0.2)
				(max_length 1)
				(best_width_ratio 0.9)
				(max_width 2)
				(curved_edges yes)
				(filter_ratio 0.9)
				(enabled yes)
				(allow_two_segments yes)
				(prefer_zone_connections yes)
			)
		)
		(pad "D105" smd rect
			(at 24.75 -8.675)
			(size 0.3 1.75)
			(layers "F.Cu" "F.Mask" "F.Paste")
			(net 65 "+12V")
			(pinfunction "VCC_12V")
			(pintype "passive")
			(teardrops
				(best_length_ratio 0.2)
				(max_length 1)
				(best_width_ratio 0.9)
				(max_width 2)
				(curved_edges yes)
				(filter_ratio 0.9)
				(enabled yes)
				(allow_two_segments yes)
				(prefer_zone_connections yes)
			)
		)
		(pad "D106" smd rect
			(at 25.25 -8.675)
			(size 0.3 1.75)
			(layers "F.Cu" "F.Mask" "F.Paste")
			(net 65 "+12V")
			(pinfunction "VCC_12V")
			(pintype "passive")
			(teardrops
				(best_length_ratio 0.2)
				(max_length 1)
				(best_width_ratio 0.9)
				(max_width 2)
				(curved_edges yes)
				(filter_ratio 0.9)
				(enabled yes)
				(allow_two_segments yes)
				(prefer_zone_connections yes)
			)
		)
		(pad "D107" smd rect
			(at 25.75 -8.675)
			(size 0.3 1.75)
			(layers "F.Cu" "F.Mask" "F.Paste")
			(net 65 "+12V")
			(pinfunction "VCC_12V")
			(pintype "passive")
			(teardrops
				(best_length_ratio 0.2)
				(max_length 1)
				(best_width_ratio 0.9)
				(max_width 2)
				(curved_edges yes)
				(filter_ratio 0.9)
				(enabled yes)
				(allow_two_segments yes)
				(prefer_zone_connections yes)
			)
		)
		(pad "D108" smd rect
			(at 26.25 -8.675)
			(size 0.3 1.75)
			(layers "F.Cu" "F.Mask" "F.Paste")
			(net 65 "+12V")
			(pinfunction "VCC_12V")
			(pintype "passive")
			(teardrops
				(best_length_ratio 0.2)
				(max_length 1)
				(best_width_ratio 0.9)
				(max_width 2)
				(curved_edges yes)
				(filter_ratio 0.9)
				(enabled yes)
				(allow_two_segments yes)
				(prefer_zone_connections yes)
			)
		)
		(pad "D109" smd rect
			(at 26.75 -8.675)
			(size 0.3 1.75)
			(layers "F.Cu" "F.Mask" "F.Paste")
			(net 65 "+12V")
			(pinfunction "VCC_12V")
			(pintype "passive")
			(teardrops
				(best_length_ratio 0.2)
				(max_length 1)
				(best_width_ratio 0.9)
				(max_width 2)
				(curved_edges yes)
				(filter_ratio 0.9)
				(enabled yes)
				(allow_two_segments yes)
				(prefer_zone_connections yes)
			)
		)
		(pad "D110" smd rect
			(at 27.25 -8.675)
			(size 0.3 1.75)
			(layers "F.Cu" "F.Mask" "F.Paste")
			(net 1 "GND")
			(pinfunction "GND(FIXED)")
			(pintype "passive")
			(teardrops
				(best_length_ratio 0.2)
				(max_length 1)
				(best_width_ratio 0.9)
				(max_width 2)
				(curved_edges yes)
				(filter_ratio 0.9)
				(enabled yes)
				(allow_two_segments yes)
				(prefer_zone_connections yes)
			)
		)
		(pad "MP" smd rect
			(at -30.575 -6 90)
			(size 3.3 1.65)
			(layers "F.Cu" "F.Mask" "F.Paste")
			(net 1 "GND")
			(pinfunction "MP")
			(pintype "passive")
			(teardrops
				(best_length_ratio 0.2)
				(max_length 1)
				(best_width_ratio 0.9)
				(max_width 2)
				(curved_edges yes)
				(filter_ratio 0.9)
				(enabled yes)
				(allow_two_segments yes)
				(prefer_zone_connections yes)
			)
		)
		(pad "MP" smd rect
			(at -30.575 6 90)
			(size 3.3 1.65)
			(layers "F.Cu" "F.Mask" "F.Paste")
			(net 1 "GND")
			(pinfunction "MP")
			(pintype "passive")
			(teardrops
				(best_length_ratio 0.2)
				(max_length 1)
				(best_width_ratio 0.9)
				(max_width 2)
				(curved_edges yes)
				(filter_ratio 0.9)
				(enabled yes)
				(allow_two_segments yes)
				(prefer_zone_connections yes)
			)
		)
	)
)
